# SCM (Grand Teton) — schematic netlist excerpt (pin names and nets, part order shuffled) for the footprints in the layout excerpt that follows; sources: Cadence DE-HDL packaged netlist, KiCad conversion of 12092022_DA0F0TMDCD0_F0T_Management_Board_D_brd_V3_OCP.brd

R52  Q_RES  4.7K 1% CHIP  pkg 0402LF  page 26 : A = P3V3_AUX ; B = TMC75_A1
R147  Q_RES  33.2 1% CHIP  pkg 0402LF  page 12 : A = SMB_BMC_MM8_R_SDA ; B = SMB_BMC_MM8_SDA

(kicad_pcb
	(version 20260206)
	(generator "pcbnew")
	(generator_version "10.0")
	(general
		(thickness 1.6)
		(legacy_teardrops no)
	)
	(paper "A4")
	(title_block
		(title "12092022_DA0F0TMDCD0_F0T_Management_Board_D_brd_V3_OCP.brd")
		(comment 1 "Grand Teton / footprints 739-740 of 1440")
	)
	(layers
		(0 "F.Cu" signal "TOP")
		(4 "In1.Cu" signal "GND")
		(6 "In2.Cu" signal "IN1")
		(8 "In3.Cu" signal "GND1")
		(10 "In4.Cu" signal "IN2")
		(12 "In5.Cu" signal "VCC")
		(14 "In6.Cu" signal "VCC1")
		(16 "In7.Cu" signal "IN3")
		(18 "In8.Cu" signal "GND2")
		(20 "In9.Cu" signal "IN4")
		(22 "In10.Cu" signal "GND3")
		(2 "B.Cu" signal "BOTTOM")
		(9 "F.Adhes" user "F.Adhesive")
		(11 "B.Adhes" user "B.Adhesive")
		(13 "F.Paste" user "Package Geometry/Pastemask Top")
		(15 "B.Paste" user "Package Geometry/Pastemask Bottom")
		(5 "F.SilkS" user "Ref Des/Silkscreen Top")
		(7 "B.SilkS" user "Ref Des/Silkscreen Bottom")
		(1 "F.Mask" user "Board Geometry/Soldermask Top")
		(3 "B.Mask" user "Board Geometry/Soldermask Bottom")
		(17 "Dwgs.User" user "User.Drawings")
		(19 "Cmts.User" user "User.Comments")
		(21 "Eco1.User" user "User.Eco1")
		(23 "Eco2.User" user "User.Eco2")
		(25 "Edge.Cuts" user "Board Geometry/Outline")
		(27 "Margin" user)
		(31 "F.CrtYd" user "Package Geometry/Place Bound Top")
		(29 "B.CrtYd" user "Package Geometry/Place Bound Bottom")
		(35 "F.Fab" user "Ref Des/Assembly Top")
		(33 "B.Fab" user "Ref Des/Assembly Bottom")
	)
	(footprint ""
		(layer "B.Cu")
		(at 57.531 -34.671 90)
		(property "Reference" "R147"
			(at 0 0 90)
			(layer "B.SilkS")
			(hide yes)
			(effects
				(font
					(size 1.27 1.27)
				)
				(justify mirror)
			)
		)
		(property "Value" ""
			(at 0 0 90)
			(layer "B.Fab")
			(effects
				(font
					(size 1.27 1.27)
				)
				(justify mirror)
			)
		)
		(duplicate_pad_numbers_are_jumpers no)
		(fp_line
			(start 0.7874 -0.4064)
			(end -0.7874 -0.4064)
			(stroke
				(width 0.1524)
				(type default)
			)
			(layer "B.SilkS")
		)
		(fp_line
			(start -0.7874 -0.4064)
			(end -0.7874 0.4064)
			(stroke
				(width 0.1524)
				(type default)
			)
			(layer "B.SilkS")
		)
		(fp_line
			(start 0.7874 0.4064)
			(end 0.7874 -0.4064)
			(stroke
				(width 0.1524)
				(type default)
			)
			(layer "B.SilkS")
		)
		(fp_line
			(start -0.7874 0.4064)
			(end 0.7874 0.4064)
			(stroke
				(width 0.1524)
				(type default)
			)
			(layer "B.SilkS")
		)
		(fp_line
			(start 0.67945 -0.305054)
			(end 0.12065 -0.305054)
			(stroke
				(width 0.1)
				(type default)
			)
			(layer "B.Fab")
		)
		(fp_line
			(start 0.12065 -0.305054)
			(end 0.12065 -0.2794)
			(stroke
				(width 0.1)
				(type default)
			)
			(layer "B.Fab")
		)
		(fp_line
			(start -0.12065 -0.3048)
			(end -0.67945 -0.3048)
			(stroke
				(width 0.1)
				(type default)
			)
			(layer "B.Fab")
		)
		(fp_line
			(start -0.67945 -0.3048)
			(end -0.67945 0.3048)
			(stroke
				(width 0.1)
				(type default)
			)
			(layer "B.Fab")
		)
		(fp_line
			(start 0.12065 -0.2794)
			(end -0.12065 -0.2794)
			(stroke
				(width 0.1)
				(type default)
			)
			(layer "B.Fab")
		)
		(fp_line
			(start -0.12065 -0.2794)
			(end -0.12065 -0.3048)
			(stroke
				(width 0.1)
				(type default)
			)
			(layer "B.Fab")
		)
		(fp_line
			(start 0.12065 0.2794)
			(end 0.12065 0.3048)
			(stroke
				(width 0.1)
				(type default)
			)
			(layer "B.Fab")
		)
		(fp_line
			(start -0.120396 0.2794)
			(end 0.12065 0.2794)
			(stroke
				(width 0.1)
				(type default)
			)
			(layer "B.Fab")
		)
		(fp_line
			(start 0.67945 0.3048)
			(end 0.67945 -0.305054)
			(stroke
				(width 0.1)
				(type default)
			)
			(layer "B.Fab")
		)
		(fp_line
			(start 0.12065 0.3048)
			(end 0.67945 0.3048)
			(stroke
				(width 0.1)
				(type default)
			)
			(layer "B.Fab")
		)
		(fp_line
			(start -0.120396 0.3048)
			(end -0.120396 0.2794)
			(stroke
				(width 0.1)
				(type default)
			)
			(layer "B.Fab")
		)
		(fp_line
			(start -0.67945 0.3048)
			(end -0.120396 0.3048)
			(stroke
				(width 0.1)
				(type default)
			)
			(layer "B.Fab")
		)
		(pad "1" smd circle
			(at 0.40005 0 270)
			(size 0 0)
			(layers "B.Cu" "B.Mask" "B.Paste")
			(net "SMB_BMC_MM8_R_SDA")
		)
		(pad "2" smd circle
			(at -0.40005 0 270)
			(size 0 0)
			(layers "B.Cu" "B.Mask" "B.Paste")
			(net "SMB_BMC_MM8_SDA")
		)
	)
	(footprint ""
		(layer "B.Cu")
		(at 20.193 -19.304 180)
		(property "Reference" "R52"
			(at 0 0 0)
			(layer "B.SilkS")
			(hide yes)
			(effects
				(font
					(size 1.27 1.27)
				)
				(justify mirror)
			)
		)
		(property "Value" ""
			(at 0 0 0)
			(layer "B.Fab")
			(effects
				(font
					(size 1.27 1.27)
				)
				(justify mirror)
			)
		)
		(duplicate_pad_numbers_are_jumpers no)
		(fp_line
			(start 0.7874 0.4064)
			(end 0.7874 -0.4064)
			(stroke
				(width 0.1524)
				(type default)
			)
			(layer "B.SilkS")
		)
		(fp_line
			(start 0.7874 -0.4064)
			(end -0.7874 -0.4064)
			(stroke
				(width 0.1524)
				(type default)
			)
			(layer "B.SilkS")
		)
		(fp_line
			(start -0.7874 0.4064)
			(end 0.7874 0.4064)
			(stroke
				(width 0.1524)
				(type default)
			)
			(layer "B.SilkS")
		)
		(fp_line
			(start -0.7874 -0.4064)
			(end -0.7874 0.4064)
			(stroke
				(width 0.1524)
				(type default)
			)
			(layer "B.SilkS")
		)
		(fp_line
			(start 0.67945 0.3048)
			(end 0.67945 -0.305054)
			(stroke
				(width 0.1)
				(type default)
			)
			(layer "B.Fab")
		)
		(fp_line
			(start 0.67945 -0.305054)
			(end 0.12065 -0.305054)
			(stroke
				(width 0.1)
				(type default)
			)
			(layer "B.Fab")
		)
		(fp_line
			(start 0.12065 0.3048)
			(end 0.67945 0.3048)
			(stroke
				(width 0.1)
				(type default)
			)
			(layer "B.Fab")
		)
		(fp_line
			(start 0.12065 0.2794)
			(end 0.12065 0.3048)
			(stroke
				(width 0.1)
				(type default)
			)
			(layer "B.Fab")
		)
		(fp_line
			(start 0.12065 -0.2794)
			(end -0.12065 -0.2794)
			(stroke
				(width 0.1)
				(type default)
			)
			(layer "B.Fab")
		)
		(fp_line
			(start 0.12065 -0.305054)
			(end 0.12065 -0.2794)
			(stroke
				(width 0.1)
				(type default)
			)
			(layer "B.Fab")
		)
		(fp_line
			(start -0.120396 0.3048)
			(end -0.120396 0.2794)
			(stroke
				(width 0.1)
				(type default)
			)
			(layer "B.Fab")
		)
		(fp_line
			(start -0.120396 0.2794)
			(end 0.12065 0.2794)
			(stroke
				(width 0.1)
				(type default)
			)
			(layer "B.Fab")
		)
		(fp_line
			(start -0.12065 -0.2794)
			(end -0.12065 -0.3048)
			(stroke
				(width 0.1)
				(type default)
			)
			(layer "B.Fab")
		)
		(fp_line
			(start -0.12065 -0.3048)
			(end -0.67945 -0.3048)
			(stroke
				(width 0.1)
				(type default)
			)
			(layer "B.Fab")
		)
		(fp_line
			(start -0.67945 0.3048)
			(end -0.120396 0.3048)
			(stroke
				(width 0.1)
				(type default)
			)
			(layer "B.Fab")
		)
		(fp_line
			(start -0.67945 -0.3048)
			(end -0.67945 0.3048)
			(stroke
				(width 0.1)
				(type default)
			)
			(layer "B.Fab")
		)
		(pad "1" smd circle
			(at 0.40005 0)
			(size 0 0)
			(layers "B.Cu" "B.Mask" "B.Paste")
			(net "P3V3_AUX")
		)
		(pad "2" smd circle
			(at -0.40005 0)
			(size 0 0)
			(layers "B.Cu" "B.Mask" "B.Paste")
			(net "TMC75_A1")
		)
	)
)
